# SCM (Grand Teton) — schematic netlist excerpt (pin names and nets, part order shuffled) for the footprints in the layout excerpt that follows; sources: Cadence DE-HDL packaged netlist, KiCad conversion of 12092022_DA0F0TMDCD0_F0T_Management_Board_D_brd_V3_OCP.brd

R140  Q_RES  4.7K 1% EMPTY  pkg 0402LF  page 27 : A = P3V3_AUX ; B = SPI_BMC_BOOT_MOSI
R64  Q_RES  0 5% EMPTY  pkg 0402LF  page 11 : A = SGPIO_CLK_0 ; B = GND

(kicad_pcb
	(version 20260206)
	(generator "pcbnew")
	(generator_version "10.0")
	(general
		(thickness 1.6)
		(legacy_teardrops no)
	)
	(paper "A4")
	(title_block
		(title "12092022_DA0F0TMDCD0_F0T_Management_Board_D_brd_V3_OCP.brd")
		(comment 1 "Grand Teton / footprints 483-484 of 1440")
	)
	(layers
		(0 "F.Cu" signal "TOP")
		(4 "In1.Cu" signal "GND")
		(6 "In2.Cu" signal "IN1")
		(8 "In3.Cu" signal "GND1")
		(10 "In4.Cu" signal "IN2")
		(12 "In5.Cu" signal "VCC")
		(14 "In6.Cu" signal "VCC1")
		(16 "In7.Cu" signal "IN3")
		(18 "In8.Cu" signal "GND2")
		(20 "In9.Cu" signal "IN4")
		(22 "In10.Cu" signal "GND3")
		(2 "B.Cu" signal "BOTTOM")
		(9 "F.Adhes" user "F.Adhesive")
		(11 "B.Adhes" user "B.Adhesive")
		(13 "F.Paste" user "Package Geometry/Pastemask Top")
		(15 "B.Paste" user "Package Geometry/Pastemask Bottom")
		(5 "F.SilkS" user "Ref Des/Silkscreen Top")
		(7 "B.SilkS" user "Ref Des/Silkscreen Bottom")
		(1 "F.Mask" user "Board Geometry/Soldermask Top")
		(3 "B.Mask" user "Board Geometry/Soldermask Bottom")
		(17 "Dwgs.User" user "User.Drawings")
		(19 "Cmts.User" user "User.Comments")
		(21 "Eco1.User" user "User.Eco1")
		(23 "Eco2.User" user "User.Eco2")
		(25 "Edge.Cuts" user "Board Geometry/Outline")
		(27 "Margin" user)
		(31 "F.CrtYd" user "Package Geometry/Place Bound Top")
		(29 "B.CrtYd" user "Package Geometry/Place Bound Bottom")
		(35 "F.Fab" user "Ref Des/Assembly Top")
		(33 "B.Fab" user "Ref Des/Assembly Bottom")
	)
	(footprint ""
		(layer "F.Cu")
		(at 46.0756 -109.5248 -90)
		(property "Reference" "R64"
			(at 0 0 270)
			(layer "F.SilkS")
			(hide yes)
			(effects
				(font
					(size 1.27 1.27)
				)
			)
		)
		(property "Value" ""
			(at 0 0 270)
			(layer "F.Fab")
			(effects
				(font
					(size 1.27 1.27)
				)
			)
		)
		(duplicate_pad_numbers_are_jumpers no)
		(fp_line
			(start -0.7874 0.4064)
			(end -0.7874 -0.4064)
			(stroke
				(width 0.1524)
				(type default)
			)
			(layer "F.SilkS")
		)
		(fp_line
			(start 0.7874 0.4064)
			(end -0.7874 0.4064)
			(stroke
				(width 0.1524)
				(type default)
			)
			(layer "F.SilkS")
		)
		(fp_line
			(start -0.7874 -0.4064)
			(end 0.7874 -0.4064)
			(stroke
				(width 0.1524)
				(type default)
			)
			(layer "F.SilkS")
		)
		(fp_line
			(start 0.7874 -0.4064)
			(end 0.7874 0.4064)
			(stroke
				(width 0.1524)
				(type default)
			)
			(layer "F.SilkS")
		)
		(fp_line
			(start -0.67945 0.3048)
			(end -0.67945 -0.305054)
			(stroke
				(width 0.1)
				(type default)
			)
			(layer "F.Fab")
		)
		(fp_line
			(start -0.12065 0.3048)
			(end -0.67945 0.3048)
			(stroke
				(width 0.1)
				(type default)
			)
			(layer "F.Fab")
		)
		(fp_line
			(start 0.120396 0.3048)
			(end 0.120396 0.2794)
			(stroke
				(width 0.1)
				(type default)
			)
			(layer "F.Fab")
		)
		(fp_line
			(start 0.67945 0.3048)
			(end 0.120396 0.3048)
			(stroke
				(width 0.1)
				(type default)
			)
			(layer "F.Fab")
		)
		(fp_line
			(start -0.12065 0.2794)
			(end -0.12065 0.3048)
			(stroke
				(width 0.1)
				(type default)
			)
			(layer "F.Fab")
		)
		(fp_line
			(start 0.120396 0.2794)
			(end -0.12065 0.2794)
			(stroke
				(width 0.1)
				(type default)
			)
			(layer "F.Fab")
		)
		(fp_line
			(start -0.12065 -0.2794)
			(end 0.12065 -0.2794)
			(stroke
				(width 0.1)
				(type default)
			)
			(layer "F.Fab")
		)
		(fp_line
			(start 0.12065 -0.2794)
			(end 0.12065 -0.3048)
			(stroke
				(width 0.1)
				(type default)
			)
			(layer "F.Fab")
		)
		(fp_line
			(start 0.12065 -0.3048)
			(end 0.67945 -0.3048)
			(stroke
				(width 0.1)
				(type default)
			)
			(layer "F.Fab")
		)
		(fp_line
			(start 0.67945 -0.3048)
			(end 0.67945 0.3048)
			(stroke
				(width 0.1)
				(type default)
			)
			(layer "F.Fab")
		)
		(fp_line
			(start -0.67945 -0.305054)
			(end -0.12065 -0.305054)
			(stroke
				(width 0.1)
				(type default)
			)
			(layer "F.Fab")
		)
		(fp_line
			(start -0.12065 -0.305054)
			(end -0.12065 -0.2794)
			(stroke
				(width 0.1)
				(type default)
			)
			(layer "F.Fab")
		)
		(pad "1" smd circle
			(at -0.40005 0 270)
			(size 0 0)
			(layers "F.Cu" "F.Mask" "F.Paste")
			(net "SGPIO_CLK_0")
		)
		(pad "2" smd circle
			(at 0.40005 0 270)
			(size 0 0)
			(layers "F.Cu" "F.Mask" "F.Paste")
			(net "GND")
		)
	)
	(footprint ""
		(layer "F.Cu")
		(at 58.039 -87.9602 90)
		(property "Reference" "R140"
			(at 0 0 90)
			(layer "F.SilkS")
			(hide yes)
			(effects
				(font
					(size 1.27 1.27)
				)
			)
		)
		(property "Value" ""
			(at 0 0 90)
			(layer "F.Fab")
			(effects
				(font
					(size 1.27 1.27)
				)
			)
		)
		(duplicate_pad_numbers_are_jumpers no)
		(fp_line
			(start 0.7874 -0.4064)
			(end 0.7874 0.4064)
			(stroke
				(width 0.1524)
				(type default)
			)
			(layer "F.SilkS")
		)
		(fp_line
			(start -0.7874 -0.4064)
			(end 0.7874 -0.4064)
			(stroke
				(width 0.1524)
				(type default)
			)
			(layer "F.SilkS")
		)
		(fp_line
			(start 0.7874 0.4064)
			(end -0.7874 0.4064)
			(stroke
				(width 0.1524)
				(type default)
			)
			(layer "F.SilkS")
		)
		(fp_line
			(start -0.7874 0.4064)
			(end -0.7874 -0.4064)
			(stroke
				(width 0.1524)
				(type default)
			)
			(layer "F.SilkS")
		)
		(fp_line
			(start -0.12065 -0.305054)
			(end -0.12065 -0.2794)
			(stroke
				(width 0.1)
				(type default)
			)
			(layer "F.Fab")
		)
		(fp_line
			(start -0.67945 -0.305054)
			(end -0.12065 -0.305054)
			(stroke
				(width 0.1)
				(type default)
			)
			(layer "F.Fab")
		)
		(fp_line
			(start 0.67945 -0.3048)
			(end 0.67945 0.3048)
			(stroke
				(width 0.1)
				(type default)
			)
			(layer "F.Fab")
		)
		(fp_line
			(start 0.12065 -0.3048)
			(end 0.67945 -0.3048)
			(stroke
				(width 0.1)
				(type default)
			)
			(layer "F.Fab")
		)
		(fp_line
			(start 0.12065 -0.2794)
			(end 0.12065 -0.3048)
			(stroke
				(width 0.1)
				(type default)
			)
			(layer "F.Fab")
		)
		(fp_line
			(start -0.12065 -0.2794)
			(end 0.12065 -0.2794)
			(stroke
				(width 0.1)
				(type default)
			)
			(layer "F.Fab")
		)
		(fp_line
			(start 0.120396 0.2794)
			(end -0.12065 0.2794)
			(stroke
				(width 0.1)
				(type default)
			)
			(layer "F.Fab")
		)
		(fp_line
			(start -0.12065 0.2794)
			(end -0.12065 0.3048)
			(stroke
				(width 0.1)
				(type default)
			)
			(layer "F.Fab")
		)
		(fp_line
			(start 0.67945 0.3048)
			(end 0.120396 0.3048)
			(stroke
				(width 0.1)
				(type default)
			)
			(layer "F.Fab")
		)
		(fp_line
			(start 0.120396 0.3048)
			(end 0.120396 0.2794)
			(stroke
				(width 0.1)
				(type default)
			)
			(layer "F.Fab")
		)
		(fp_line
			(start -0.12065 0.3048)
			(end -0.67945 0.3048)
			(stroke
				(width 0.1)
				(type default)
			)
			(layer "F.Fab")
		)
		(fp_line
			(start -0.67945 0.3048)
			(end -0.67945 -0.305054)
			(stroke
				(width 0.1)
				(type default)
			)
			(layer "F.Fab")
		)
		(pad "1" smd circle
			(at -0.40005 0 90)
			(size 0 0)
			(layers "F.Cu" "F.Mask" "F.Paste")
			(net "P3V3_AUX")
		)
		(pad "2" smd circle
			(at 0.40005 0 90)
			(size 0 0)
			(layers "F.Cu" "F.Mask" "F.Paste")
			(net "SPI_BMC_BOOT_MOSI")
		)
	)
)
